# T6G (Grand Teton) — schematic netlist excerpt (pin names and nets, part order shuffled) for the footprints in the layout excerpt that follows; sources: Cadence DE-HDL packaged netlist, KiCad conversion of 04192023_DAF0TMB3IC0_F0TG_MB_C_brd_V02_OCP.brd

PC530  Q_CAPP  390UF 2.5V 20% ALUM  pkg SMLF  page 225 : A = PVDD11_S3_P1 ; B = GND
R4187  Q_RES  1K 1% CHIP  pkg 0402LF  page 235 : A = U272_2_ADD2 ; B = GND
C1100  Q_CAP_DIFFBUS  DIFF BUS_0.22UF 6.3V 20% X6S  pkg C0201  page 67 : \1\ = P3E_CPU1_P4_TX_C_DP<2> ; \2\ = P3E_CPU1_P4_TX_DP<2>

(kicad_pcb
	(version 20260206)
	(generator "pcbnew")
	(generator_version "10.0")
	(general
		(thickness 1.6)
		(legacy_teardrops no)
	)
	(paper "A4")
	(title_block
		(title "04192023_DAF0TMB3IC0_F0TG_MB_C_brd_V02_OCP.brd")
		(comment 1 "Grand Teton / footprints 2131-2133 of 8354")
	)
	(layers
		(0 "F.Cu" signal "TOP")
		(4 "In1.Cu" signal "GND")
		(6 "In2.Cu" signal "IN1")
		(8 "In3.Cu" signal "GND1")
		(10 "In4.Cu" signal "IN2")
		(12 "In5.Cu" signal "GND2")
		(14 "In6.Cu" signal "IN3")
		(16 "In7.Cu" signal "GND3")
		(18 "In8.Cu" signal "VCC")
		(20 "In9.Cu" signal "VCC1")
		(22 "In10.Cu" signal "GND4")
		(24 "In11.Cu" signal "IN4")
		(26 "In12.Cu" signal "GND5")
		(28 "In13.Cu" signal "IN5")
		(30 "In14.Cu" signal "GND6")
		(32 "In15.Cu" signal "IN6")
		(34 "In16.Cu" signal "GND7")
		(2 "B.Cu" signal "BOTTOM")
		(9 "F.Adhes" user "F.Adhesive")
		(11 "B.Adhes" user "B.Adhesive")
		(13 "F.Paste" user "Package Geometry/Pastemask Top")
		(15 "B.Paste" user "Package Geometry/Pastemask Bottom")
		(5 "F.SilkS" user "Ref Des/Silkscreen Top")
		(7 "B.SilkS" user "Ref Des/Silkscreen Bottom")
		(1 "F.Mask" user "Board Geometry/Soldermask Top")
		(3 "B.Mask" user "Board Geometry/Soldermask Bottom")
		(17 "Dwgs.User" user "User.Drawings")
		(19 "Cmts.User" user "User.Comments")
		(21 "Eco1.User" user "User.Eco1")
		(23 "Eco2.User" user "User.Eco2")
		(25 "Edge.Cuts" user "Board Geometry/Outline")
		(27 "Margin" user)
		(31 "F.CrtYd" user "Package Geometry/Place Bound Top")
		(29 "B.CrtYd" user "Package Geometry/Place Bound Bottom")
		(35 "F.Fab" user "Ref Des/Assembly Top")
		(33 "B.Fab" user "Ref Des/Assembly Bottom")
	)
	(footprint ""
		(layer "F.Cu")
		(at 194.218306 -332.744572 -90)
		(property "Reference" "PC530"
			(at -4.24434 17.347692 90)
			(unlocked yes)
			(layer "F.SilkS")
			(effects
				(font
					(size 0.7874 0.5842)
					(thickness 0.1524)
				)
				(justify left)
			)
		)
		(property "Value" ""
			(at 0 0 270)
			(layer "F.Fab")
			(effects
				(font
					(size 1.27 1.27)
				)
			)
		)
		(duplicate_pad_numbers_are_jumpers no)
		(fp_line
			(start -1.988058 2.750058)
			(end 2.750058 2.750058)
			(stroke
				(width 0.1524)
				(type default)
			)
			(layer "F.SilkS")
		)
		(fp_line
			(start 2.750058 2.750058)
			(end 2.750058 0.9398)
			(stroke
				(width 0.1524)
				(type default)
			)
			(layer "F.SilkS")
		)
		(fp_line
			(start -2.750058 1.988058)
			(end -1.988058 2.750058)
			(stroke
				(width 0.1524)
				(type default)
			)
			(layer "F.SilkS")
		)
		(fp_line
			(start -2.750058 0.9398)
			(end -2.750058 1.988058)
			(stroke
				(width 0.1524)
				(type default)
			)
			(layer "F.SilkS")
		)
		(fp_line
			(start 2.750058 -0.9398)
			(end 2.750058 -2.750058)
			(stroke
				(width 0.1524)
				(type default)
			)
			(layer "F.SilkS")
		)
		(fp_line
			(start -2.750058 -1.988058)
			(end -2.750058 -0.9398)
			(stroke
				(width 0.1524)
				(type default)
			)
			(layer "F.SilkS")
		)
		(fp_line
			(start -1.988058 -2.750058)
			(end -2.750058 -1.988058)
			(stroke
				(width 0.1524)
				(type default)
			)
			(layer "F.SilkS")
		)
		(fp_line
			(start 2.750058 -2.750058)
			(end -1.988058 -2.750058)
			(stroke
				(width 0.1524)
				(type default)
			)
			(layer "F.SilkS")
		)
		(fp_line
			(start -2.750058 2.750058)
			(end 2.750058 2.750058)
			(stroke
				(width 0.1)
				(type default)
			)
			(layer "F.Fab")
		)
		(fp_line
			(start 2.750058 2.750058)
			(end 2.750058 -2.750058)
			(stroke
				(width 0.1)
				(type default)
			)
			(layer "F.Fab")
		)
		(fp_line
			(start -2.750058 -2.750058)
			(end -2.750058 2.750058)
			(stroke
				(width 0.1)
				(type default)
			)
			(layer "F.Fab")
		)
		(fp_line
			(start 2.750058 -2.750058)
			(end -2.750058 -2.750058)
			(stroke
				(width 0.1)
				(type default)
			)
			(layer "F.Fab")
		)
		(pad "1" smd rect
			(at -2.199894 0)
			(size 1.6002 3.0226)
			(layers "F.Cu" "F.Mask" "F.Paste")
			(net "PVDD11_S3_P1")
		)
		(pad "2" smd rect
			(at 2.199894 0)
			(size 1.6002 3.0226)
			(layers "F.Cu" "F.Mask" "F.Paste")
			(net "GND")
		)
	)
	(footprint ""
		(layer "F.Cu")
		(at 101.555296 -422.43248 90)
		(property "Reference" "R4187"
			(at 0 0 90)
			(layer "F.SilkS")
			(hide yes)
			(effects
				(font
					(size 1.27 1.27)
				)
			)
		)
		(property "Value" ""
			(at 0 0 90)
			(layer "F.Fab")
			(effects
				(font
					(size 1.27 1.27)
				)
			)
		)
		(duplicate_pad_numbers_are_jumpers no)
		(fp_line
			(start 0.7874 -0.4064)
			(end 0.7874 0.4064)
			(stroke
				(width 0.1524)
				(type default)
			)
			(layer "F.SilkS")
		)
		(fp_line
			(start -0.7874 -0.4064)
			(end 0.7874 -0.4064)
			(stroke
				(width 0.1524)
				(type default)
			)
			(layer "F.SilkS")
		)
		(fp_line
			(start 0.7874 0.4064)
			(end -0.7874 0.4064)
			(stroke
				(width 0.1524)
				(type default)
			)
			(layer "F.SilkS")
		)
		(fp_line
			(start -0.7874 0.4064)
			(end -0.7874 -0.4064)
			(stroke
				(width 0.1524)
				(type default)
			)
			(layer "F.SilkS")
		)
		(fp_line
			(start -0.12065 -0.305054)
			(end -0.12065 -0.2794)
			(stroke
				(width 0.1)
				(type default)
			)
			(layer "F.Fab")
		)
		(fp_line
			(start -0.67945 -0.305054)
			(end -0.12065 -0.305054)
			(stroke
				(width 0.1)
				(type default)
			)
			(layer "F.Fab")
		)
		(fp_line
			(start 0.67945 -0.3048)
			(end 0.67945 0.3048)
			(stroke
				(width 0.1)
				(type default)
			)
			(layer "F.Fab")
		)
		(fp_line
			(start 0.12065 -0.3048)
			(end 0.67945 -0.3048)
			(stroke
				(width 0.1)
				(type default)
			)
			(layer "F.Fab")
		)
		(fp_line
			(start 0.12065 -0.2794)
			(end 0.12065 -0.3048)
			(stroke
				(width 0.1)
				(type default)
			)
			(layer "F.Fab")
		)
		(fp_line
			(start -0.12065 -0.2794)
			(end 0.12065 -0.2794)
			(stroke
				(width 0.1)
				(type default)
			)
			(layer "F.Fab")
		)
		(fp_line
			(start 0.120396 0.2794)
			(end -0.12065 0.2794)
			(stroke
				(width 0.1)
				(type default)
			)
			(layer "F.Fab")
		)
		(fp_line
			(start -0.12065 0.2794)
			(end -0.12065 0.3048)
			(stroke
				(width 0.1)
				(type default)
			)
			(layer "F.Fab")
		)
		(fp_line
			(start 0.67945 0.3048)
			(end 0.120396 0.3048)
			(stroke
				(width 0.1)
				(type default)
			)
			(layer "F.Fab")
		)
		(fp_line
			(start 0.120396 0.3048)
			(end 0.120396 0.2794)
			(stroke
				(width 0.1)
				(type default)
			)
			(layer "F.Fab")
		)
		(fp_line
			(start -0.12065 0.3048)
			(end -0.67945 0.3048)
			(stroke
				(width 0.1)
				(type default)
			)
			(layer "F.Fab")
		)
		(fp_line
			(start -0.67945 0.3048)
			(end -0.67945 -0.305054)
			(stroke
				(width 0.1)
				(type default)
			)
			(layer "F.Fab")
		)
		(pad "1" smd circle
			(at -0.40005 0 90)
			(size 0 0)
			(layers "F.Cu" "F.Mask" "F.Paste")
			(net "U272_2_ADD2")
		)
		(pad "2" smd circle
			(at 0.40005 0 90)
			(size 0 0)
			(layers "F.Cu" "F.Mask" "F.Paste")
			(net "GND")
		)
	)
	(footprint ""
		(layer "F.Cu")
		(at 180.528468 -50.060098)
		(property "Reference" "C1100"
			(at 0 0 0)
			(layer "F.SilkS")
			(hide yes)
			(effects
				(font
					(size 1.27 1.27)
				)
			)
		)
		(property "Value" ""
			(at 0 0 0)
			(layer "F.Fab")
			(effects
				(font
					(size 1.27 1.27)
				)
			)
		)
		(duplicate_pad_numbers_are_jumpers no)
		(fp_line
			(start -0.299974 -0.150114)
			(end 0.299974 -0.150114)
			(stroke
				(width 0.1)
				(type default)
			)
			(layer "F.Fab")
		)
		(fp_line
			(start -0.299974 0.150114)
			(end -0.299974 -0.150114)
			(stroke
				(width 0.1)
				(type default)
			)
			(layer "F.Fab")
		)
		(fp_line
			(start 0.299974 -0.150114)
			(end 0.299974 0.150114)
			(stroke
				(width 0.1)
				(type default)
			)
			(layer "F.Fab")
		)
		(fp_line
			(start 0.299974 0.150114)
			(end -0.299974 0.150114)
			(stroke
				(width 0.1)
				(type default)
			)
			(layer "F.Fab")
		)
		(pad "1" smd rect
			(at -0.2667 0)
			(size 0.3048 0.381)
			(layers "F.Cu" "F.Mask" "F.Paste")
			(net "P3E_CPU1_P4_TX_C_DP<2>")
		)
		(pad "2" smd rect
			(at 0.2667 0)
			(size 0.3048 0.381)
			(layers "F.Cu" "F.Mask" "F.Paste")
			(net "P3E_CPU1_P4_TX_DP<2>")
		)
	)
)
